(kicad_pcb
	(version 20260206)
	(generator "pcbnew")
	(generator_version "10.0")
	(general
		(thickness 1.6)
		(legacy_teardrops no)
	)
	(paper "A4")
	(title_block
		(title "04192023_DAF0TMB3IC0_F0TG_MB_C_brd_V02_OCP.brd")
		(comment 1 "Grand Teton / footprints 6103-6108 of 8354")
	)
	(layers
		(0 "F.Cu" signal "TOP")
		(4 "In1.Cu" signal "GND")
		(6 "In2.Cu" signal "IN1")
		(8 "In3.Cu" signal "GND1")
		(10 "In4.Cu" signal "IN2")
		(12 "In5.Cu" signal "GND2")
		(14 "In6.Cu" signal "IN3")
		(16 "In7.Cu" signal "GND3")
		(18 "In8.Cu" signal "VCC")
		(20 "In9.Cu" signal "VCC1")
		(22 "In10.Cu" signal "GND4")
		(24 "In11.Cu" signal "IN4")
		(26 "In12.Cu" signal "GND5")
		(28 "In13.Cu" signal "IN5")
		(30 "In14.Cu" signal "GND6")
		(32 "In15.Cu" signal "IN6")
		(34 "In16.Cu" signal "GND7")
		(2 "B.Cu" signal "BOTTOM")
		(9 "F.Adhes" user "F.Adhesive")
		(11 "B.Adhes" user "B.Adhesive")
		(13 "F.Paste" user "Package Geometry/Pastemask Top")
		(15 "B.Paste" user "Package Geometry/Pastemask Bottom")
		(5 "F.SilkS" user "Ref Des/Silkscreen Top")
		(7 "B.SilkS" user "Ref Des/Silkscreen Bottom")
		(1 "F.Mask" user "Board Geometry/Soldermask Top")
		(3 "B.Mask" user "Board Geometry/Soldermask Bottom")
		(17 "Dwgs.User" user "User.Drawings")
		(19 "Cmts.User" user "User.Comments")
		(21 "Eco1.User" user "User.Eco1")
		(23 "Eco2.User" user "User.Eco2")
		(25 "Edge.Cuts" user "Board Geometry/Outline")
		(27 "Margin" user)
		(31 "F.CrtYd" user "Package Geometry/Place Bound Top")
		(29 "B.CrtYd" user "Package Geometry/Place Bound Bottom")
		(35 "F.Fab" user "Ref Des/Assembly Top")
		(33 "B.Fab" user "Ref Des/Assembly Bottom")
	)
	(footprint ""
		(layer "B.Cu")
		(at 366.288574 7.622794)
		(property "Reference" "J116"
			(at 4.461002 1.607058 270)
			(unlocked yes)
			(layer "B.SilkS")
			(effects
				(font
					(size 0.7874 0.5842)
					(thickness 0.1524)
				)
				(justify left mirror)
			)
		)
		(property "Value" ""
			(at 0 0 0)
			(layer "B.Fab")
			(effects
				(font
					(size 1.27 1.27)
				)
				(justify mirror)
			)
		)
		(duplicate_pad_numbers_are_jumpers no)
		(fp_line
			(start -1.2192 -2.06756)
			(end -1.2192 2.06756)
			(stroke
				(width 0.1524)
				(type default)
			)
			(layer "B.SilkS")
		)
		(fp_line
			(start -1.2192 2.06756)
			(end 1.2192 2.06756)
			(stroke
				(width 0.1524)
				(type default)
			)
			(layer "B.SilkS")
		)
		(fp_line
			(start 1.2192 -2.06756)
			(end -1.2192 -2.06756)
			(stroke
				(width 0.1524)
				(type default)
			)
			(layer "B.SilkS")
		)
		(fp_line
			(start 1.2192 2.06756)
			(end 1.2192 -2.06756)
			(stroke
				(width 0.1524)
				(type default)
			)
			(layer "B.SilkS")
		)
		(pad "" np_thru_hole circle
			(at -3.4671 -1.27 270)
			(size 1.0414 1.0414)
			(drill 1.0414)
			(layers "*.Cu" "*.Mask")
			(clearance 0.381)
			(thermal_gap 0.381)
		)
		(pad "" np_thru_hole circle
			(at -3.4671 1.27 270)
			(size 1.0414 1.0414)
			(drill 1.0414)
			(layers "*.Cu" "*.Mask")
			(clearance 0.381)
			(thermal_gap 0.381)
		)
		(pad "" np_thru_hole circle
			(at 2.8829 -1.27 270)
			(size 1.0414 1.0414)
			(drill 1.0414)
			(layers "*.Cu" "*.Mask")
			(clearance 0.381)
			(thermal_gap 0.381)
		)
		(pad "" np_thru_hole circle
			(at 2.8829 1.27 270)
			(size 1.0414 1.0414)
			(drill 1.0414)
			(layers "*.Cu" "*.Mask")
			(clearance 0.381)
			(thermal_gap 0.381)
		)
		(pad "1" smd rect
			(at -0.8255 -0.249936 270)
			(size 0.3048 0.508)
			(layers "B.Cu" "B.Mask" "B.Paste")
			(net "DELTA_L_85_5INCH_IN5_DN")
		)
		(pad "2" smd rect
			(at -0.8255 0.249936 270)
			(size 0.3048 0.508)
			(layers "B.Cu" "B.Mask" "B.Paste")
			(net "DELTA_L_85_5INCH_IN5_DP")
		)
		(pad "3" smd circle
			(at 0 0 180)
			(size 0 0)
			(layers "B.Cu" "B.Mask" "B.Paste")
			(net "DELTA_L_GND_1")
		)
		(zone
			(layers "F.Cu" "B.Cu" "In1.Cu" "In2.Cu" "In3.Cu" "In4.Cu" "In5.Cu" "In6.Cu"
				"In7.Cu" "In8.Cu" "In9.Cu" "In10.Cu" "In11.Cu" "In12.Cu" "In13.Cu" "In14.Cu"
				"In15.Cu" "In16.Cu"
			)
			(hatch none 0.5)
			(connect_pads
				(clearance 0)
			)
			(min_thickness 0.25)
			(keepout
				(tracks not_allowed)
				(vias allowed)
				(pads allowed)
				(copperpour not_allowed)
				(footprints allowed)
			)
			(placement
				(enabled no)
				(sheetname "")
			)
			(fill
				(thermal_gap 0.5)
				(thermal_bridge_width 0.5)
				(island_removal_mode 0)
			)
			(polygon
				(pts
					(arc
						(start 363.748574 6.352794)
						(mid 361.894374 6.352794)
						(end 363.748574 6.352794)
					)
				)
			)
		)
		(zone
			(layers "F.Cu" "B.Cu" "In1.Cu" "In2.Cu" "In3.Cu" "In4.Cu" "In5.Cu" "In6.Cu"
				"In7.Cu" "In8.Cu" "In9.Cu" "In10.Cu" "In11.Cu" "In12.Cu" "In13.Cu" "In14.Cu"
				"In15.Cu" "In16.Cu"
			)
			(hatch none 0.5)
			(connect_pads
				(clearance 0)
			)
			(min_thickness 0.25)
			(keepout
				(tracks not_allowed)
				(vias allowed)
				(pads allowed)
				(copperpour not_allowed)
				(footprints allowed)
			)
			(placement
				(enabled no)
				(sheetname "")
			)
			(fill
				(thermal_gap 0.5)
				(thermal_bridge_width 0.5)
				(island_removal_mode 0)
			)
			(polygon
				(pts
					(arc
						(start 363.748574 8.892794)
						(mid 361.894374 8.892794)
						(end 363.748574 8.892794)
					)
				)
			)
		)
		(zone
			(layers "F.Cu" "B.Cu" "In1.Cu" "In2.Cu" "In3.Cu" "In4.Cu" "In5.Cu" "In6.Cu"
				"In7.Cu" "In8.Cu" "In9.Cu" "In10.Cu" "In11.Cu" "In12.Cu" "In13.Cu" "In14.Cu"
				"In15.Cu" "In16.Cu"
			)
			(hatch none 0.5)
			(connect_pads
				(clearance 0)
			)
			(min_thickness 0.25)
			(keepout
				(tracks not_allowed)
				(vias allowed)
				(pads allowed)
				(copperpour not_allowed)
				(footprints allowed)
			)
			(placement
				(enabled no)
				(sheetname "")
			)
			(fill
				(thermal_gap 0.5)
				(thermal_bridge_width 0.5)
				(island_removal_mode 0)
			)
			(polygon
				(pts
					(arc
						(start 370.098574 6.352794)
						(mid 368.244374 6.352794)
						(end 370.098574 6.352794)
					)
				)
			)
		)
		(zone
			(layers "F.Cu" "B.Cu" "In1.Cu" "In2.Cu" "In3.Cu" "In4.Cu" "In5.Cu" "In6.Cu"
				"In7.Cu" "In8.Cu" "In9.Cu" "In10.Cu" "In11.Cu" "In12.Cu" "In13.Cu" "In14.Cu"
				"In15.Cu" "In16.Cu"
			)
			(hatch none 0.5)
			(connect_pads
				(clearance 0)
			)
			(min_thickness 0.25)
			(keepout
				(tracks not_allowed)
				(vias allowed)
				(pads allowed)
				(copperpour not_allowed)
				(footprints allowed)
			)
			(placement
				(enabled no)
				(sheetname "")
			)
			(fill
				(thermal_gap 0.5)
				(thermal_bridge_width 0.5)
				(island_removal_mode 0)
			)
			(polygon
				(pts
					(arc
						(start 370.098574 8.892794)
						(mid 368.244374 8.892794)
						(end 370.098574 8.892794)
					)
				)
			)
		)
		(zone
			(layer "B.Cu")
			(hatch none 0.5)
			(connect_pads
				(clearance 0)
			)
			(min_thickness 0.25)
			(keepout
				(tracks not_allowed)
				(vias allowed)
				(pads allowed)
				(copperpour not_allowed)
				(footprints allowed)
			)
			(placement
				(enabled no)
				(sheetname "")
			)
			(fill
				(thermal_gap 0.5)
				(thermal_bridge_width 0.5)
				(island_removal_mode 0)
			)
			(polygon
				(pts
					(xy 365.170974 7.074154) (xy 365.170974 7.169658) (xy 365.767874 7.169658) (xy 365.767874 7.576058)
					(xy 365.170974 7.576058) (xy 365.170974 7.66953) (xy 365.767874 7.66953) (xy 365.767874 8.07593)
					(xy 365.170974 8.07593) (xy 365.170974 8.171434) (xy 365.869474 8.171434) (xy 365.869474 7.074154)
				)
			)
		)
	)
	(footprint ""
		(layer "B.Cu")
		(at 399.969482 -416.899344 90)
		(property "Reference" "C6616"
			(at 0 0 90)
			(layer "B.SilkS")
			(hide yes)
			(effects
				(font
					(size 1.27 1.27)
				)
				(justify mirror)
			)
		)
		(property "Value" ""
			(at 0 0 90)
			(layer "B.Fab")
			(effects
				(font
					(size 1.27 1.27)
				)
				(justify mirror)
			)
		)
		(duplicate_pad_numbers_are_jumpers no)
		(fp_line
			(start 0.299974 -0.150114)
			(end -0.299974 -0.150114)
			(stroke
				(width 0.1)
				(type default)
			)
			(layer "B.Fab")
		)
		(fp_line
			(start -0.299974 -0.150114)
			(end -0.299974 0.150114)
			(stroke
				(width 0.1)
				(type default)
			)
			(layer "B.Fab")
		)
		(fp_line
			(start 0.299974 0.150114)
			(end 0.299974 -0.150114)
			(stroke
				(width 0.1)
				(type default)
			)
			(layer "B.Fab")
		)
		(fp_line
			(start -0.299974 0.150114)
			(end 0.299974 0.150114)
			(stroke
				(width 0.1)
				(type default)
			)
			(layer "B.Fab")
		)
		(pad "1" smd rect
			(at 0.2667 0 270)
			(size 0.3048 0.381)
			(layers "B.Cu" "B.Mask" "B.Paste")
			(net "P5E_CPU0_P3_TX_BUF_C_DN<9>")
		)
		(pad "2" smd rect
			(at -0.2667 0 270)
			(size 0.3048 0.381)
			(layers "B.Cu" "B.Mask" "B.Paste")
			(net "P5E_CPU0_P3_TX_BUF_DN<9>")
		)
	)
	(footprint ""
		(layer "B.Cu")
		(at 98.962464 -267.529564)
		(property "Reference" "C2662"
			(at 0 0 0)
			(layer "B.SilkS")
			(hide yes)
			(effects
				(font
					(size 1.27 1.27)
				)
				(justify mirror)
			)
		)
		(property "Value" ""
			(at 0 0 0)
			(layer "B.Fab")
			(effects
				(font
					(size 1.27 1.27)
				)
				(justify mirror)
			)
		)
		(duplicate_pad_numbers_are_jumpers no)
		(fp_line
			(start -0.7874 -0.4064)
			(end -0.7874 0.4064)
			(stroke
				(width 0.1524)
				(type default)
			)
			(layer "B.SilkS")
		)
		(fp_line
			(start -0.7874 0.4064)
			(end 0.7874 0.4064)
			(stroke
				(width 0.1524)
				(type default)
			)
			(layer "B.SilkS")
		)
		(fp_line
			(start 0.7874 -0.4064)
			(end -0.7874 -0.4064)
			(stroke
				(width 0.1524)
				(type default)
			)
			(layer "B.SilkS")
		)
		(fp_line
			(start 0.7874 0.4064)
			(end 0.7874 -0.4064)
			(stroke
				(width 0.1524)
				(type default)
			)
			(layer "B.SilkS")
		)
		(fp_line
			(start -0.67945 -0.3048)
			(end -0.67945 0.3048)
			(stroke
				(width 0.1)
				(type default)
			)
			(layer "B.Fab")
		)
		(fp_line
			(start -0.67945 0.3048)
			(end -0.120396 0.3048)
			(stroke
				(width 0.1)
				(type default)
			)
			(layer "B.Fab")
		)
		(fp_line
			(start -0.12065 -0.3048)
			(end -0.67945 -0.3048)
			(stroke
				(width 0.1)
				(type default)
			)
			(layer "B.Fab")
		)
		(fp_line
			(start -0.12065 -0.2794)
			(end -0.12065 -0.3048)
			(stroke
				(width 0.1)
				(type default)
			)
			(layer "B.Fab")
		)
		(fp_line
			(start -0.120396 0.2794)
			(end 0.12065 0.2794)
			(stroke
				(width 0.1)
				(type default)
			)
			(layer "B.Fab")
		)
		(fp_line
			(start -0.120396 0.3048)
			(end -0.120396 0.2794)
			(stroke
				(width 0.1)
				(type default)
			)
			(layer "B.Fab")
		)
		(fp_line
			(start 0.12065 -0.305054)
			(end 0.12065 -0.2794)
			(stroke
				(width 0.1)
				(type default)
			)
			(layer "B.Fab")
		)
		(fp_line
			(start 0.12065 -0.2794)
			(end -0.12065 -0.2794)
			(stroke
				(width 0.1)
				(type default)
			)
			(layer "B.Fab")
		)
		(fp_line
			(start 0.12065 0.2794)
			(end 0.12065 0.3048)
			(stroke
				(width 0.1)
				(type default)
			)
			(layer "B.Fab")
		)
		(fp_line
			(start 0.12065 0.3048)
			(end 0.67945 0.3048)
			(stroke
				(width 0.1)
				(type default)
			)
			(layer "B.Fab")
		)
		(fp_line
			(start 0.67945 -0.305054)
			(end 0.12065 -0.305054)
			(stroke
				(width 0.1)
				(type default)
			)
			(layer "B.Fab")
		)
		(fp_line
			(start 0.67945 0.3048)
			(end 0.67945 -0.305054)
			(stroke
				(width 0.1)
				(type default)
			)
			(layer "B.Fab")
		)
		(pad "1" smd circle
			(at 0.40005 0 180)
			(size 0 0)
			(layers "B.Cu" "B.Mask" "B.Paste")
			(net "PVDD_33_S5")
		)
		(pad "2" smd circle
			(at -0.40005 0 180)
			(size 0 0)
			(layers "B.Cu" "B.Mask" "B.Paste")
			(net "GND")
		)
	)
	(footprint ""
		(layer "B.Cu")
		(at 375.41835 -396.393162 -90)
		(property "Reference" "C1021"
			(at 0 0 90)
			(layer "B.SilkS")
			(hide yes)
			(effects
				(font
					(size 1.27 1.27)
				)
				(justify mirror)
			)
		)
		(property "Value" ""
			(at 0 0 90)
			(layer "B.Fab")
			(effects
				(font
					(size 1.27 1.27)
				)
				(justify mirror)
			)
		)
		(duplicate_pad_numbers_are_jumpers no)
		(fp_line
			(start -0.299974 0.150114)
			(end 0.299974 0.150114)
			(stroke
				(width 0.1)
				(type default)
			)
			(layer "B.Fab")
		)
		(fp_line
			(start 0.299974 0.150114)
			(end 0.299974 -0.150114)
			(stroke
				(width 0.1)
				(type default)
			)
			(layer "B.Fab")
		)
		(fp_line
			(start -0.299974 -0.150114)
			(end -0.299974 0.150114)
			(stroke
				(width 0.1)
				(type default)
			)
			(layer "B.Fab")
		)
		(fp_line
			(start 0.299974 -0.150114)
			(end -0.299974 -0.150114)
			(stroke
				(width 0.1)
				(type default)
			)
			(layer "B.Fab")
		)
		(pad "1" smd rect
			(at 0.2667 0 90)
			(size 0.3048 0.381)
			(layers "B.Cu" "B.Mask" "B.Paste")
			(net "P0V9_CPU0_RT3_2A_2D")
		)
		(pad "2" smd rect
			(at -0.2667 0 90)
			(size 0.3048 0.381)
			(layers "B.Cu" "B.Mask" "B.Paste")
			(net "GND")
		)
	)
	(footprint ""
		(layer "B.Cu")
		(at 205.28788 -35.956748 90)
		(property "Reference" "C2022"
			(at 0 0 90)
			(layer "B.SilkS")
			(hide yes)
			(effects
				(font
					(size 1.27 1.27)
				)
				(justify mirror)
			)
		)
		(property "Value" ""
			(at 0 0 90)
			(layer "B.Fab")
			(effects
				(font
					(size 1.27 1.27)
				)
				(justify mirror)
			)
		)
		(duplicate_pad_numbers_are_jumpers no)
		(fp_line
			(start 0.7874 -0.4064)
			(end -0.7874 -0.4064)
			(stroke
				(width 0.1524)
				(type default)
			)
			(layer "B.SilkS")
		)
		(fp_line
			(start -0.7874 -0.4064)
			(end -0.7874 0.4064)
			(stroke
				(width 0.1524)
				(type default)
			)
			(layer "B.SilkS")
		)
		(fp_line
			(start 0.7874 0.4064)
			(end 0.7874 -0.4064)
			(stroke
				(width 0.1524)
				(type default)
			)
			(layer "B.SilkS")
		)
		(fp_line
			(start -0.7874 0.4064)
			(end 0.7874 0.4064)
			(stroke
				(width 0.1524)
				(type default)
			)
			(layer "B.SilkS")
		)
		(fp_line
			(start 0.67945 -0.305054)
			(end 0.12065 -0.305054)
			(stroke
				(width 0.1)
				(type default)
			)
			(layer "B.Fab")
		)
		(fp_line
			(start 0.12065 -0.305054)
			(end 0.12065 -0.2794)
			(stroke
				(width 0.1)
				(type default)
			)
			(layer "B.Fab")
		)
		(fp_line
			(start -0.12065 -0.3048)
			(end -0.67945 -0.3048)
			(stroke
				(width 0.1)
				(type default)
			)
			(layer "B.Fab")
		)
		(fp_line
			(start -0.67945 -0.3048)
			(end -0.67945 0.3048)
			(stroke
				(width 0.1)
				(type default)
			)
			(layer "B.Fab")
		)
		(fp_line
			(start 0.12065 -0.2794)
			(end -0.12065 -0.2794)
			(stroke
				(width 0.1)
				(type default)
			)
			(layer "B.Fab")
		)
		(fp_line
			(start -0.12065 -0.2794)
			(end -0.12065 -0.3048)
			(stroke
				(width 0.1)
				(type default)
			)
			(layer "B.Fab")
		)
		(fp_line
			(start 0.12065 0.2794)
			(end 0.12065 0.3048)
			(stroke
				(width 0.1)
				(type default)
			)
			(layer "B.Fab")
		)
		(fp_line
			(start -0.120396 0.2794)
			(end 0.12065 0.2794)
			(stroke
				(width 0.1)
				(type default)
			)
			(layer "B.Fab")
		)
		(fp_line
			(start 0.67945 0.3048)
			(end 0.67945 -0.305054)
			(stroke
				(width 0.1)
				(type default)
			)
			(layer "B.Fab")
		)
		(fp_line
			(start 0.12065 0.3048)
			(end 0.67945 0.3048)
			(stroke
				(width 0.1)
				(type default)
			)
			(layer "B.Fab")
		)
		(fp_line
			(start -0.120396 0.3048)
			(end -0.120396 0.2794)
			(stroke
				(width 0.1)
				(type default)
			)
			(layer "B.Fab")
		)
		(fp_line
			(start -0.67945 0.3048)
			(end -0.120396 0.3048)
			(stroke
				(width 0.1)
				(type default)
			)
			(layer "B.Fab")
		)
		(pad "1" smd circle
			(at 0.40005 0 270)
			(size 0 0)
			(layers "B.Cu" "B.Mask" "B.Paste")
			(net "VSENSE_P12V_INA230_5_INP")
		)
		(pad "2" smd circle
			(at -0.40005 0 270)
			(size 0 0)
			(layers "B.Cu" "B.Mask" "B.Paste")
			(net "VSENSE_P12V_INA230_5_INN")
		)
	)
	(footprint ""
		(layer "B.Cu")
		(at 170.424856 -8.062468 -90)
		(property "Reference" "R3858"
			(at 0 0 90)
			(layer "B.SilkS")
			(hide yes)
			(effects
				(font
					(size 1.27 1.27)
				)
				(justify mirror)
			)
		)
		(property "Value" ""
			(at 0 0 90)
			(layer "B.Fab")
			(effects
				(font
					(size 1.27 1.27)
				)
				(justify mirror)
			)
		)
		(duplicate_pad_numbers_are_jumpers no)
		(fp_line
			(start -0.7874 0.4064)
			(end 0.7874 0.4064)
			(stroke
				(width 0.1524)
				(type default)
			)
			(layer "B.SilkS")
		)
		(fp_line
			(start 0.7874 0.4064)
			(end 0.7874 -0.4064)
			(stroke
				(width 0.1524)
				(type default)
			)
			(layer "B.SilkS")
		)
		(fp_line
			(start -0.7874 -0.4064)
			(end -0.7874 0.4064)
			(stroke
				(width 0.1524)
				(type default)
			)
			(layer "B.SilkS")
		)
		(fp_line
			(start 0.7874 -0.4064)
			(end -0.7874 -0.4064)
			(stroke
				(width 0.1524)
				(type default)
			)
			(layer "B.SilkS")
		)
		(fp_line
			(start -0.67945 0.3048)
			(end -0.120396 0.3048)
			(stroke
				(width 0.1)
				(type default)
			)
			(layer "B.Fab")
		)
		(fp_line
			(start -0.120396 0.3048)
			(end -0.120396 0.2794)
			(stroke
				(width 0.1)
				(type default)
			)
			(layer "B.Fab")
		)
		(fp_line
			(start 0.12065 0.3048)
			(end 0.67945 0.3048)
			(stroke
				(width 0.1)
				(type default)
			)
			(layer "B.Fab")
		)
		(fp_line
			(start 0.67945 0.3048)
			(end 0.67945 -0.305054)
			(stroke
				(width 0.1)
				(type default)
			)
			(layer "B.Fab")
		)
		(fp_line
			(start -0.120396 0.2794)
			(end 0.12065 0.2794)
			(stroke
				(width 0.1)
				(type default)
			)
			(layer "B.Fab")
		)
		(fp_line
			(start 0.12065 0.2794)
			(end 0.12065 0.3048)
			(stroke
				(width 0.1)
				(type default)
			)
			(layer "B.Fab")
		)
		(fp_line
			(start -0.12065 -0.2794)
			(end -0.12065 -0.3048)
			(stroke
				(width 0.1)
				(type default)
			)
			(layer "B.Fab")
		)
		(fp_line
			(start 0.12065 -0.2794)
			(end -0.12065 -0.2794)
			(stroke
				(width 0.1)
				(type default)
			)
			(layer "B.Fab")
		)
		(fp_line
			(start -0.67945 -0.3048)
			(end -0.67945 0.3048)
			(stroke
				(width 0.1)
				(type default)
			)
			(layer "B.Fab")
		)
		(fp_line
			(start -0.12065 -0.3048)
			(end -0.67945 -0.3048)
			(stroke
				(width 0.1)
				(type default)
			)
			(layer "B.Fab")
		)
		(fp_line
			(start 0.12065 -0.305054)
			(end 0.12065 -0.2794)
			(stroke
				(width 0.1)
				(type default)
			)
			(layer "B.Fab")
		)
		(fp_line
			(start 0.67945 -0.305054)
			(end 0.12065 -0.305054)
			(stroke
				(width 0.1)
				(type default)
			)
			(layer "B.Fab")
		)
		(pad "1" smd circle
			(at 0.40005 0 90)
			(size 0 0)
			(layers "B.Cu" "B.Mask" "B.Paste")
			(net "SMB_OCP_V3_2_3V3AUX_SDA")
		)
		(pad "2" smd circle
			(at -0.40005 0 90)
			(size 0 0)
			(layers "B.Cu" "B.Mask" "B.Paste")
			(net "SMB_OCP_V3_2_3V3AUX_SDA_R0")
		)
	)
)
